(kicad_pcb
	(version 20260206)
	(generator "pcbnew")
	(generator_version "10.0")
	(general
		(thickness 1.6)
		(legacy_teardrops no)
	)
	(paper "A4")
	(title_block
		(title "baseboard — 13948-1b.1110WZS1818.brd")
		(comment 1 "Honey Badger (Wiwynn) / footprints 580-586 of 2523")
	)
	(layers
		(0 "F.Cu" signal "TOP")
		(4 "In1.Cu" signal "L2GND")
		(6 "In2.Cu" signal "L3")
		(8 "In3.Cu" signal "L4VCC")
		(10 "In4.Cu" signal "L5VCC")
		(12 "In5.Cu" signal "L6")
		(14 "In6.Cu" signal "L7GND")
		(2 "B.Cu" signal "BOTTOM")
		(9 "F.Adhes" user "F.Adhesive")
		(11 "B.Adhes" user "B.Adhesive")
		(13 "F.Paste" user "Package Geometry/Pastemask Top")
		(15 "B.Paste" user "Package Geometry/Pastemask Bottom")
		(5 "F.SilkS" user "Ref Des/Silkscreen Top")
		(7 "B.SilkS" user "Ref Des/Silkscreen Bottom")
		(1 "F.Mask" user "Board Geometry/Soldermask Top")
		(3 "B.Mask" user "Board Geometry/Soldermask Bottom")
		(17 "Dwgs.User" user "User.Drawings")
		(19 "Cmts.User" user "User.Comments")
		(21 "Eco1.User" user "User.Eco1")
		(23 "Eco2.User" user "User.Eco2")
		(25 "Edge.Cuts" user "Board Geometry/Outline")
		(27 "Margin" user)
		(31 "F.CrtYd" user "Package Geometry/Place Bound Top")
		(29 "B.CrtYd" user "Package Geometry/Place Bound Bottom")
		(35 "F.Fab" user "Ref Des/Assembly Top")
		(33 "B.Fab" user "Ref Des/Assembly Bottom")
	)
	(footprint ""
		(layer "F.Cu")
		(at 186.554872 -194.051936 -90)
		(property "Reference" "R429"
			(at 0 0 270)
			(layer "F.SilkS")
			(hide yes)
			(effects
				(font
					(size 1.27 1.27)
				)
			)
		)
		(property "Value" "2KR2F-3-GP"
			(at 0.064008 -3.993896 270)
			(unlocked yes)
			(layer "F.Fab")
			(hide yes)
			(effects
				(font
					(size 1.016 1.016)
					(thickness 0.1524)
				)
			)
		)
		(property "Device Type" "R402H16"
			(at 0.064008 -5.517896 270)
			(unlocked yes)
			(layer "F.Fab")
			(hide yes)
			(effects
				(font
					(size 1.016 1.016)
					(thickness 0.1524)
				)
			)
		)
		(duplicate_pad_numbers_are_jumpers no)
		(fp_line
			(start -0.508 -0.9398)
			(end -0.508 0.9398)
			(stroke
				(width 0.1524)
				(type default)
			)
			(layer "F.SilkS")
		)
		(fp_line
			(start 0.508 -0.9398)
			(end -0.508 -0.9398)
			(stroke
				(width 0.1524)
				(type default)
			)
			(layer "F.SilkS")
		)
		(fp_rect
			(start -0.508 0.9398)
			(end 0.508 -0.9398)
			(stroke
				(width 0)
				(type default)
			)
			(fill no)
			(layer "F.CrtYd")
		)
		(fp_rect
			(start -0.508 0.9398)
			(end 0.508 -0.9398)
			(stroke
				(width 0)
				(type default)
			)
			(fill no)
			(layer "F.Fab")
		)
		(pad "1" smd custom
			(at 0 -0.4445 270)
			(size 0.1397 0.1397)
			(layers "F.Cu" "F.Mask" "F.Paste")
			(net "P3V3_STBY")
			(options
				(clearance outline)
				(anchor circle)
			)
			(primitives
				(gr_poly
					(pts
						(arc
							(start -0.1778 -0.2794)
							(mid -0.249642 -0.249642)
							(end -0.2794 -0.1778)
						)
						(arc
							(start -0.2794 0.1778)
							(mid -0.249642 0.249642)
							(end -0.1778 0.2794)
						)
						(arc
							(start 0.1778 0.2794)
							(mid 0.249642 0.249642)
							(end 0.2794 0.1778)
						)
						(arc
							(start 0.2794 -0.1778)
							(mid 0.249642 -0.249642)
							(end 0.1778 -0.2794)
						)
					)
					(width 0)
					(fill yes)
				)
			)
		)
		(pad "2" smd custom
			(at 0 0.4445 270)
			(size 0.1397 0.1397)
			(layers "F.Cu" "F.Mask" "F.Paste")
			(net "SAS_I2C_C_BUF_SDA")
			(options
				(clearance outline)
				(anchor circle)
			)
			(primitives
				(gr_poly
					(pts
						(arc
							(start -0.1778 -0.2794)
							(mid -0.249642 -0.249642)
							(end -0.2794 -0.1778)
						)
						(arc
							(start -0.2794 0.1778)
							(mid -0.249642 0.249642)
							(end -0.1778 0.2794)
						)
						(arc
							(start 0.1778 0.2794)
							(mid 0.249642 0.249642)
							(end 0.2794 0.1778)
						)
						(arc
							(start 0.2794 -0.1778)
							(mid 0.249642 -0.249642)
							(end 0.1778 -0.2794)
						)
					)
					(width 0)
					(fill yes)
				)
			)
		)
	)
	(footprint ""
		(layer "F.Cu")
		(at 103.886 -232.537 90)
		(property "Reference" "R595"
			(at 0 0 90)
			(layer "F.SilkS")
			(hide yes)
			(effects
				(font
					(size 1.27 1.27)
				)
			)
		)
		(property "Value" "0R2J-2-GP"
			(at 0.064008 -3.993896 90)
			(unlocked yes)
			(layer "F.Fab")
			(hide yes)
			(effects
				(font
					(size 1.016 1.016)
					(thickness 0.1524)
				)
			)
		)
		(property "Device Type" "R402H16"
			(at 0.064008 -5.517896 90)
			(unlocked yes)
			(layer "F.Fab")
			(hide yes)
			(effects
				(font
					(size 1.016 1.016)
					(thickness 0.1524)
				)
			)
		)
		(duplicate_pad_numbers_are_jumpers no)
		(fp_line
			(start 0.508 -0.9398)
			(end -0.508 -0.9398)
			(stroke
				(width 0.1524)
				(type default)
			)
			(layer "F.SilkS")
		)
		(fp_line
			(start -0.508 -0.9398)
			(end -0.508 0.9398)
			(stroke
				(width 0.1524)
				(type default)
			)
			(layer "F.SilkS")
		)
		(fp_rect
			(start -0.508 0.9398)
			(end 0.508 -0.9398)
			(stroke
				(width 0)
				(type default)
			)
			(fill no)
			(layer "F.CrtYd")
		)
		(fp_rect
			(start -0.508 0.9398)
			(end 0.508 -0.9398)
			(stroke
				(width 0)
				(type default)
			)
			(fill no)
			(layer "F.Fab")
		)
		(pad "1" smd custom
			(at 0 -0.4445 90)
			(size 0.1397 0.1397)
			(layers "F.Cu" "F.Mask" "F.Paste")
			(net "SAS_FAULT_LED6")
			(options
				(clearance outline)
				(anchor circle)
			)
			(primitives
				(gr_poly
					(pts
						(arc
							(start -0.1778 -0.2794)
							(mid -0.249642 -0.249642)
							(end -0.2794 -0.1778)
						)
						(arc
							(start -0.2794 0.1778)
							(mid -0.249642 0.249642)
							(end -0.1778 0.2794)
						)
						(arc
							(start 0.1778 0.2794)
							(mid 0.249642 0.249642)
							(end 0.2794 0.1778)
						)
						(arc
							(start 0.2794 -0.1778)
							(mid 0.249642 -0.249642)
							(end 0.1778 -0.2794)
						)
					)
					(width 0)
					(fill yes)
				)
			)
		)
		(pad "2" smd custom
			(at 0 0.4445 90)
			(size 0.1397 0.1397)
			(layers "F.Cu" "F.Mask" "F.Paste")
			(net "SAS_HDD_LED_6")
			(options
				(clearance outline)
				(anchor circle)
			)
			(primitives
				(gr_poly
					(pts
						(arc
							(start -0.1778 -0.2794)
							(mid -0.249642 -0.249642)
							(end -0.2794 -0.1778)
						)
						(arc
							(start -0.2794 0.1778)
							(mid -0.249642 0.249642)
							(end -0.1778 0.2794)
						)
						(arc
							(start 0.1778 0.2794)
							(mid 0.249642 0.249642)
							(end 0.2794 0.1778)
						)
						(arc
							(start 0.2794 -0.1778)
							(mid 0.249642 -0.249642)
							(end 0.1778 -0.2794)
						)
					)
					(width 0)
					(fill yes)
				)
			)
		)
	)
	(footprint ""
		(layer "F.Cu")
		(at 167.989504 -24.184356 180)
		(property "Reference" "R413"
			(at 0 0 180)
			(layer "F.SilkS")
			(hide yes)
			(effects
				(font
					(size 1.27 1.27)
				)
			)
		)
		(property "Value" "0R2J-2-GP"
			(at 0.064008 -3.993896 180)
			(unlocked yes)
			(layer "F.Fab")
			(hide yes)
			(effects
				(font
					(size 1.016 1.016)
					(thickness 0.1524)
				)
			)
		)
		(property "Device Type" "R402H16"
			(at 0.064008 -5.517896 180)
			(unlocked yes)
			(layer "F.Fab")
			(hide yes)
			(effects
				(font
					(size 1.016 1.016)
					(thickness 0.1524)
				)
			)
		)
		(duplicate_pad_numbers_are_jumpers no)
		(fp_line
			(start 0.508 -0.9398)
			(end -0.508 -0.9398)
			(stroke
				(width 0.1524)
				(type default)
			)
			(layer "F.SilkS")
		)
		(fp_line
			(start -0.508 -0.9398)
			(end -0.508 0.9398)
			(stroke
				(width 0.1524)
				(type default)
			)
			(layer "F.SilkS")
		)
		(fp_rect
			(start -0.508 0.9398)
			(end 0.508 -0.9398)
			(stroke
				(width 0)
				(type default)
			)
			(fill no)
			(layer "F.CrtYd")
		)
		(fp_rect
			(start -0.508 0.9398)
			(end 0.508 -0.9398)
			(stroke
				(width 0)
				(type default)
			)
			(fill no)
			(layer "F.Fab")
		)
		(pad "1" smd custom
			(at 0 -0.4445 180)
			(size 0.1397 0.1397)
			(layers "F.Cu" "F.Mask" "F.Paste")
			(net "RJ45_GND_1")
			(options
				(clearance outline)
				(anchor circle)
			)
			(primitives
				(gr_poly
					(pts
						(arc
							(start -0.1778 -0.2794)
							(mid -0.249642 -0.249642)
							(end -0.2794 -0.1778)
						)
						(arc
							(start -0.2794 0.1778)
							(mid -0.249642 0.249642)
							(end -0.1778 0.2794)
						)
						(arc
							(start 0.1778 0.2794)
							(mid 0.249642 0.249642)
							(end 0.2794 0.1778)
						)
						(arc
							(start 0.2794 -0.1778)
							(mid 0.249642 -0.249642)
							(end 0.1778 -0.2794)
						)
					)
					(width 0)
					(fill yes)
				)
			)
		)
		(pad "2" smd custom
			(at 0 0.4445 180)
			(size 0.1397 0.1397)
			(layers "F.Cu" "F.Mask" "F.Paste")
			(net "GND")
			(options
				(clearance outline)
				(anchor circle)
			)
			(primitives
				(gr_poly
					(pts
						(arc
							(start -0.1778 -0.2794)
							(mid -0.249642 -0.249642)
							(end -0.2794 -0.1778)
						)
						(arc
							(start -0.2794 0.1778)
							(mid -0.249642 0.249642)
							(end -0.1778 0.2794)
						)
						(arc
							(start 0.1778 0.2794)
							(mid 0.249642 0.249642)
							(end 0.2794 0.1778)
						)
						(arc
							(start 0.2794 -0.1778)
							(mid 0.249642 -0.249642)
							(end 0.1778 -0.2794)
						)
					)
					(width 0)
					(fill yes)
				)
			)
		)
	)
	(footprint ""
		(layer "F.Cu")
		(at 331.161136 -197.366128 180)
		(property "Reference" "R192"
			(at 0 0 180)
			(layer "F.SilkS")
			(hide yes)
			(effects
				(font
					(size 1.27 1.27)
				)
			)
		)
		(property "Value" "8K2R2J-3-GP"
			(at 0.064008 -3.993896 180)
			(unlocked yes)
			(layer "F.Fab")
			(hide yes)
			(effects
				(font
					(size 1.016 1.016)
					(thickness 0.1524)
				)
			)
		)
		(property "Device Type" "R402H16"
			(at 0.064008 -5.517896 180)
			(unlocked yes)
			(layer "F.Fab")
			(hide yes)
			(effects
				(font
					(size 1.016 1.016)
					(thickness 0.1524)
				)
			)
		)
		(duplicate_pad_numbers_are_jumpers no)
		(fp_line
			(start 0.508 -0.9398)
			(end -0.508 -0.9398)
			(stroke
				(width 0.1524)
				(type default)
			)
			(layer "F.SilkS")
		)
		(fp_line
			(start -0.508 -0.9398)
			(end -0.508 0.9398)
			(stroke
				(width 0.1524)
				(type default)
			)
			(layer "F.SilkS")
		)
		(fp_rect
			(start -0.508 0.9398)
			(end 0.508 -0.9398)
			(stroke
				(width 0)
				(type default)
			)
			(fill no)
			(layer "F.CrtYd")
		)
		(fp_rect
			(start -0.508 0.9398)
			(end 0.508 -0.9398)
			(stroke
				(width 0)
				(type default)
			)
			(fill no)
			(layer "F.Fab")
		)
		(pad "1" smd custom
			(at 0 -0.4445 180)
			(size 0.1397 0.1397)
			(layers "F.Cu" "F.Mask" "F.Paste")
			(net "P3V3_STBY")
			(options
				(clearance outline)
				(anchor circle)
			)
			(primitives
				(gr_poly
					(pts
						(arc
							(start -0.1778 -0.2794)
							(mid -0.249642 -0.249642)
							(end -0.2794 -0.1778)
						)
						(arc
							(start -0.2794 0.1778)
							(mid -0.249642 0.249642)
							(end -0.1778 0.2794)
						)
						(arc
							(start 0.1778 0.2794)
							(mid 0.249642 0.249642)
							(end 0.2794 0.1778)
						)
						(arc
							(start 0.2794 -0.1778)
							(mid 0.249642 -0.249642)
							(end 0.1778 -0.2794)
						)
					)
					(width 0)
					(fill yes)
				)
			)
		)
		(pad "2" smd custom
			(at 0 0.4445 180)
			(size 0.1397 0.1397)
			(layers "F.Cu" "F.Mask" "F.Paste")
			(net "EEPROM_A0_R")
			(options
				(clearance outline)
				(anchor circle)
			)
			(primitives
				(gr_poly
					(pts
						(arc
							(start -0.1778 -0.2794)
							(mid -0.249642 -0.249642)
							(end -0.2794 -0.1778)
						)
						(arc
							(start -0.2794 0.1778)
							(mid -0.249642 0.249642)
							(end -0.1778 0.2794)
						)
						(arc
							(start 0.1778 0.2794)
							(mid 0.249642 0.249642)
							(end 0.2794 0.1778)
						)
						(arc
							(start 0.2794 -0.1778)
							(mid 0.249642 -0.249642)
							(end 0.1778 -0.2794)
						)
					)
					(width 0)
					(fill yes)
				)
			)
		)
	)
	(footprint ""
		(layer "F.Cu")
		(at 76.816966 -85.344 -90)
		(property "Reference" "SC1227"
			(at 0 0 270)
			(layer "F.SilkS")
			(hide yes)
			(effects
				(font
					(size 1.27 1.27)
				)
			)
		)
		(property "Value" "SCD1U6D3V1KX-GP"
			(at -2.8321 -1.7399 270)
			(unlocked yes)
			(layer "F.Fab")
			(hide yes)
			(effects
				(font
					(size 1.016 1.016)
					(thickness 0.1524)
				)
			)
		)
		(property "Device Type" "C0201H13"
			(at -2.8321 -3.2639 270)
			(unlocked yes)
			(layer "F.Fab")
			(hide yes)
			(effects
				(font
					(size 1.016 1.016)
					(thickness 0.1524)
				)
			)
		)
		(duplicate_pad_numbers_are_jumpers no)
		(fp_rect
			(start -0.2794 0.6477)
			(end 0.2794 -0.6477)
			(stroke
				(width 0)
				(type default)
			)
			(fill no)
			(layer "F.CrtYd")
		)
		(fp_rect
			(start -0.2794 0.6477)
			(end 0.2794 -0.6477)
			(stroke
				(width 0)
				(type default)
			)
			(fill no)
			(layer "F.Fab")
		)
		(pad "1" smd custom
			(at 0 -0.2794 270)
			(size 0.0762 0.0762)
			(layers "F.Cu" "F.Mask" "F.Paste")
			(net "P1V8_E")
			(options
				(clearance outline)
				(anchor circle)
			)
			(primitives
				(gr_poly
					(pts
						(arc
							(start 0.1524 -0.127)
							(mid 0.137521 -0.162921)
							(end 0.1016 -0.1778)
						)
						(arc
							(start -0.1016 -0.1778)
							(mid -0.137521 -0.162921)
							(end -0.1524 -0.127)
						)
						(arc
							(start -0.1524 0.127)
							(mid -0.137521 0.162921)
							(end -0.1016 0.1778)
						)
						(arc
							(start 0.1016 0.1778)
							(mid 0.137521 0.162921)
							(end 0.1524 0.127)
						)
					)
					(width 0)
					(fill yes)
				)
			)
		)
		(pad "2" smd custom
			(at 0 0.2794 270)
			(size 0.0762 0.0762)
			(layers "F.Cu" "F.Mask" "F.Paste")
			(net "GND")
			(options
				(clearance outline)
				(anchor circle)
			)
			(primitives
				(gr_poly
					(pts
						(arc
							(start 0.1524 -0.127)
							(mid 0.137521 -0.162921)
							(end 0.1016 -0.1778)
						)
						(arc
							(start -0.1016 -0.1778)
							(mid -0.137521 -0.162921)
							(end -0.1524 -0.127)
						)
						(arc
							(start -0.1524 0.127)
							(mid -0.137521 0.162921)
							(end -0.1016 0.1778)
						)
						(arc
							(start 0.1016 0.1778)
							(mid 0.137521 0.162921)
							(end 0.1524 0.127)
						)
					)
					(width 0)
					(fill yes)
				)
			)
		)
	)
	(footprint ""
		(layer "F.Cu")
		(at 150.622 -92.456 180)
		(property "Reference" "SC1170"
			(at 0 0 180)
			(layer "F.SilkS")
			(hide yes)
			(effects
				(font
					(size 1.27 1.27)
				)
			)
		)
		(property "Value" "SC100U6D3V0MX-2GP"
			(at -0.00254 -4.78536 180)
			(unlocked yes)
			(layer "F.Fab")
			(hide yes)
			(effects
				(font
					(size 1.016 1.016)
					(thickness 0.1524)
				)
			)
		)
		(property "Device Type" "C1210H107"
			(at -0.00254 -6.38048 180)
			(unlocked yes)
			(layer "F.Fab")
			(hide yes)
			(effects
				(font
					(size 1.016 1.016)
					(thickness 0.1524)
				)
			)
		)
		(duplicate_pad_numbers_are_jumpers no)
		(fp_line
			(start 1.5748 2.3368)
			(end 1.5748 0.762)
			(stroke
				(width 0.1524)
				(type default)
			)
			(layer "F.SilkS")
		)
		(fp_line
			(start 1.5748 -0.762)
			(end 1.5748 -2.3368)
			(stroke
				(width 0.1524)
				(type default)
			)
			(layer "F.SilkS")
		)
		(fp_line
			(start 1.5748 -2.3368)
			(end -1.5748 -2.3368)
			(stroke
				(width 0.1524)
				(type default)
			)
			(layer "F.SilkS")
		)
		(fp_line
			(start -1.5748 2.3368)
			(end 1.5748 2.3368)
			(stroke
				(width 0.1524)
				(type default)
			)
			(layer "F.SilkS")
		)
		(fp_line
			(start -1.5748 0.762)
			(end -1.5748 2.3368)
			(stroke
				(width 0.1524)
				(type default)
			)
			(layer "F.SilkS")
		)
		(fp_line
			(start -1.5748 -2.3368)
			(end -1.5748 -0.762)
			(stroke
				(width 0.1524)
				(type default)
			)
			(layer "F.SilkS")
		)
		(fp_rect
			(start -1.651 2.413)
			(end 1.651 -2.413)
			(stroke
				(width 0)
				(type default)
			)
			(fill no)
			(layer "F.CrtYd")
		)
		(fp_poly
			(pts
				(xy 1.651 2.413) (xy 1.651 -2.413) (xy -1.651 -2.413) (xy -1.651 2.413)
			)
			(stroke
				(width 0)
				(type default)
			)
			(fill no)
			(layer "F.Fab")
		)
		(pad "1" smd rect
			(at 0 -1.4732 180)
			(size 2.794 1.397)
			(layers "F.Cu" "F.Mask" "F.Paste")
			(net "GND")
		)
		(pad "2" smd rect
			(at 0 1.4732 180)
			(size 2.794 1.397)
			(layers "F.Cu" "F.Mask" "F.Paste")
			(net "GB_VDDA")
		)
	)
	(footprint ""
		(layer "F.Cu")
		(at 105.16997 -76.454)
		(property "Reference" "SR803"
			(at 0 0 0)
			(layer "F.SilkS")
			(hide yes)
			(effects
				(font
					(size 1.27 1.27)
				)
			)
		)
		(property "Value" "4K75R2F-1-GP"
			(at 0.064008 -3.993896 0)
			(unlocked yes)
			(layer "F.Fab")
			(hide yes)
			(effects
				(font
					(size 1.016 1.016)
					(thickness 0.1524)
				)
			)
		)
		(property "Device Type" "R402H16"
			(at 0.064008 -5.517896 0)
			(unlocked yes)
			(layer "F.Fab")
			(hide yes)
			(effects
				(font
					(size 1.016 1.016)
					(thickness 0.1524)
				)
			)
		)
		(duplicate_pad_numbers_are_jumpers no)
		(fp_line
			(start -0.508 -0.9398)
			(end -0.508 0.9398)
			(stroke
				(width 0.1524)
				(type default)
			)
			(layer "F.SilkS")
		)
		(fp_line
			(start 0.508 -0.9398)
			(end -0.508 -0.9398)
			(stroke
				(width 0.1524)
				(type default)
			)
			(layer "F.SilkS")
		)
		(fp_rect
			(start -0.508 0.9398)
			(end 0.508 -0.9398)
			(stroke
				(width 0)
				(type default)
			)
			(fill no)
			(layer "F.CrtYd")
		)
		(fp_rect
			(start -0.508 0.9398)
			(end 0.508 -0.9398)
			(stroke
				(width 0)
				(type default)
			)
			(fill no)
			(layer "F.Fab")
		)
		(pad "1" smd custom
			(at 0 -0.4445)
			(size 0.1397 0.1397)
			(layers "F.Cu" "F.Mask" "F.Paste")
			(net "LSI_TRST_N")
			(options
				(clearance outline)
				(anchor circle)
			)
			(primitives
				(gr_poly
					(pts
						(arc
							(start -0.1778 -0.2794)
							(mid -0.249642 -0.249642)
							(end -0.2794 -0.1778)
						)
						(arc
							(start -0.2794 0.1778)
							(mid -0.249642 0.249642)
							(end -0.1778 0.2794)
						)
						(arc
							(start 0.1778 0.2794)
							(mid 0.249642 0.249642)
							(end 0.2794 0.1778)
						)
						(arc
							(start 0.2794 -0.1778)
							(mid 0.249642 -0.249642)
							(end 0.1778 -0.2794)
						)
					)
					(width 0)
					(fill yes)
				)
			)
		)
		(pad "2" smd custom
			(at 0 0.4445)
			(size 0.1397 0.1397)
			(layers "F.Cu" "F.Mask" "F.Paste")
			(net "GND")
			(options
				(clearance outline)
				(anchor circle)
			)
			(primitives
				(gr_poly
					(pts
						(arc
							(start -0.1778 -0.2794)
							(mid -0.249642 -0.249642)
							(end -0.2794 -0.1778)
						)
						(arc
							(start -0.2794 0.1778)
							(mid -0.249642 0.249642)
							(end -0.1778 0.2794)
						)
						(arc
							(start 0.1778 0.2794)
							(mid 0.249642 0.249642)
							(end 0.2794 0.1778)
						)
						(arc
							(start 0.2794 -0.1778)
							(mid 0.249642 -0.249642)
							(end 0.1778 -0.2794)
						)
					)
					(width 0)
					(fill yes)
				)
			)
		)
	)
)
